# T6G (Grand Teton) — schematic netlist excerpt (pin names and nets, part order shuffled) for the footprints in the layout excerpt that follows; sources: Cadence DE-HDL packaged netlist, KiCad conversion of 04192023_DAF0TMB3IC0_F0TG_MB_C_brd_V02_OCP.brd

R6854  Q_RES  33 5% CHIP  pkg 0402LF  page 81 : A = P0V9_RETIMER_CPU0_EN ; B = P0V9_RETIMER_CPU0_EN_R2
C89  Q_CAP  10UF 25V 10% X6S  pkg C0805  page 86 : A = P12V_MEM_CPU0 ; B = GND
C673  Q_CAP  1UF 4V 20% X6S  pkg 0201  page 301 : A = P1V8_CPU0_RT2_1A ; B = GND

(kicad_pcb
	(version 20260206)
	(generator "pcbnew")
	(generator_version "10.0")
	(general
		(thickness 1.6)
		(legacy_teardrops no)
	)
	(paper "A4")
	(title_block
		(title "04192023_DAF0TMB3IC0_F0TG_MB_C_brd_V02_OCP.brd")
		(comment 1 "Grand Teton / footprints 6036-6038 of 8354")
	)
	(layers
		(0 "F.Cu" signal "TOP")
		(4 "In1.Cu" signal "GND")
		(6 "In2.Cu" signal "IN1")
		(8 "In3.Cu" signal "GND1")
		(10 "In4.Cu" signal "IN2")
		(12 "In5.Cu" signal "GND2")
		(14 "In6.Cu" signal "IN3")
		(16 "In7.Cu" signal "GND3")
		(18 "In8.Cu" signal "VCC")
		(20 "In9.Cu" signal "VCC1")
		(22 "In10.Cu" signal "GND4")
		(24 "In11.Cu" signal "IN4")
		(26 "In12.Cu" signal "GND5")
		(28 "In13.Cu" signal "IN5")
		(30 "In14.Cu" signal "GND6")
		(32 "In15.Cu" signal "IN6")
		(34 "In16.Cu" signal "GND7")
		(2 "B.Cu" signal "BOTTOM")
		(9 "F.Adhes" user "F.Adhesive")
		(11 "B.Adhes" user "B.Adhesive")
		(13 "F.Paste" user "Package Geometry/Pastemask Top")
		(15 "B.Paste" user "Package Geometry/Pastemask Bottom")
		(5 "F.SilkS" user "Ref Des/Silkscreen Top")
		(7 "B.SilkS" user "Ref Des/Silkscreen Bottom")
		(1 "F.Mask" user "Board Geometry/Soldermask Top")
		(3 "B.Mask" user "Board Geometry/Soldermask Bottom")
		(17 "Dwgs.User" user "User.Drawings")
		(19 "Cmts.User" user "User.Comments")
		(21 "Eco1.User" user "User.Eco1")
		(23 "Eco2.User" user "User.Eco2")
		(25 "Edge.Cuts" user "Board Geometry/Outline")
		(27 "Margin" user)
		(31 "F.CrtYd" user "Package Geometry/Place Bound Top")
		(29 "B.CrtYd" user "Package Geometry/Place Bound Bottom")
		(35 "F.Fab" user "Ref Des/Assembly Top")
		(33 "B.Fab" user "Ref Des/Assembly Bottom")
	)
	(footprint ""
		(layer "B.Cu")
		(at 196.977 -112.395)
		(property "Reference" "R6854"
			(at 0 0 0)
			(layer "B.SilkS")
			(hide yes)
			(effects
				(font
					(size 1.27 1.27)
				)
				(justify mirror)
			)
		)
		(property "Value" ""
			(at 0 0 0)
			(layer "B.Fab")
			(effects
				(font
					(size 1.27 1.27)
				)
				(justify mirror)
			)
		)
		(duplicate_pad_numbers_are_jumpers no)
		(fp_line
			(start -0.7874 -0.4064)
			(end -0.7874 0.4064)
			(stroke
				(width 0.1524)
				(type default)
			)
			(layer "B.SilkS")
		)
		(fp_line
			(start -0.7874 0.4064)
			(end 0.7874 0.4064)
			(stroke
				(width 0.1524)
				(type default)
			)
			(layer "B.SilkS")
		)
		(fp_line
			(start 0.7874 -0.4064)
			(end -0.7874 -0.4064)
			(stroke
				(width 0.1524)
				(type default)
			)
			(layer "B.SilkS")
		)
		(fp_line
			(start 0.7874 0.4064)
			(end 0.7874 -0.4064)
			(stroke
				(width 0.1524)
				(type default)
			)
			(layer "B.SilkS")
		)
		(fp_line
			(start -0.67945 -0.3048)
			(end -0.67945 0.3048)
			(stroke
				(width 0.1)
				(type default)
			)
			(layer "B.Fab")
		)
		(fp_line
			(start -0.67945 0.3048)
			(end -0.120396 0.3048)
			(stroke
				(width 0.1)
				(type default)
			)
			(layer "B.Fab")
		)
		(fp_line
			(start -0.12065 -0.3048)
			(end -0.67945 -0.3048)
			(stroke
				(width 0.1)
				(type default)
			)
			(layer "B.Fab")
		)
		(fp_line
			(start -0.12065 -0.2794)
			(end -0.12065 -0.3048)
			(stroke
				(width 0.1)
				(type default)
			)
			(layer "B.Fab")
		)
		(fp_line
			(start -0.120396 0.2794)
			(end 0.12065 0.2794)
			(stroke
				(width 0.1)
				(type default)
			)
			(layer "B.Fab")
		)
		(fp_line
			(start -0.120396 0.3048)
			(end -0.120396 0.2794)
			(stroke
				(width 0.1)
				(type default)
			)
			(layer "B.Fab")
		)
		(fp_line
			(start 0.12065 -0.305054)
			(end 0.12065 -0.2794)
			(stroke
				(width 0.1)
				(type default)
			)
			(layer "B.Fab")
		)
		(fp_line
			(start 0.12065 -0.2794)
			(end -0.12065 -0.2794)
			(stroke
				(width 0.1)
				(type default)
			)
			(layer "B.Fab")
		)
		(fp_line
			(start 0.12065 0.2794)
			(end 0.12065 0.3048)
			(stroke
				(width 0.1)
				(type default)
			)
			(layer "B.Fab")
		)
		(fp_line
			(start 0.12065 0.3048)
			(end 0.67945 0.3048)
			(stroke
				(width 0.1)
				(type default)
			)
			(layer "B.Fab")
		)
		(fp_line
			(start 0.67945 -0.305054)
			(end 0.12065 -0.305054)
			(stroke
				(width 0.1)
				(type default)
			)
			(layer "B.Fab")
		)
		(fp_line
			(start 0.67945 0.3048)
			(end 0.67945 -0.305054)
			(stroke
				(width 0.1)
				(type default)
			)
			(layer "B.Fab")
		)
		(pad "1" smd circle
			(at 0.40005 0 180)
			(size 0 0)
			(layers "B.Cu" "B.Mask" "B.Paste")
			(net "P0V9_RETIMER_CPU0_EN")
		)
		(pad "2" smd circle
			(at -0.40005 0 180)
			(size 0 0)
			(layers "B.Cu" "B.Mask" "B.Paste")
			(net "P0V9_RETIMER_CPU0_EN_R2")
		)
	)
	(footprint ""
		(layer "B.Cu")
		(at 307.368194 -192.660016)
		(property "Reference" "C89"
			(at 0 0 0)
			(layer "B.SilkS")
			(hide yes)
			(effects
				(font
					(size 1.27 1.27)
				)
				(justify mirror)
			)
		)
		(property "Value" ""
			(at 0 0 0)
			(layer "B.Fab")
			(effects
				(font
					(size 1.27 1.27)
				)
				(justify mirror)
			)
		)
		(duplicate_pad_numbers_are_jumpers no)
		(fp_line
			(start -1.524 -0.762)
			(end -1.524 0.762)
			(stroke
				(width 0.1524)
				(type default)
			)
			(layer "B.SilkS")
		)
		(fp_line
			(start -1.524 0.762)
			(end 1.524 0.762)
			(stroke
				(width 0.1524)
				(type default)
			)
			(layer "B.SilkS")
		)
		(fp_line
			(start 1.524 -0.762)
			(end -1.524 -0.762)
			(stroke
				(width 0.1524)
				(type default)
			)
			(layer "B.SilkS")
		)
		(fp_line
			(start 1.524 0.762)
			(end 1.524 -0.762)
			(stroke
				(width 0.1524)
				(type default)
			)
			(layer "B.SilkS")
		)
		(fp_line
			(start -1.1049 -0.724916)
			(end 1.1049 -0.724916)
			(stroke
				(width 0.1)
				(type default)
			)
			(layer "B.Fab")
		)
		(fp_line
			(start -1.1049 0.724916)
			(end -1.1049 -0.724916)
			(stroke
				(width 0.1)
				(type default)
			)
			(layer "B.Fab")
		)
		(fp_line
			(start 1.1049 -0.724916)
			(end 1.1049 0.724916)
			(stroke
				(width 0.1)
				(type default)
			)
			(layer "B.Fab")
		)
		(fp_line
			(start 1.1049 0.724916)
			(end -1.1049 0.724916)
			(stroke
				(width 0.1)
				(type default)
			)
			(layer "B.Fab")
		)
		(pad "1" smd rect
			(at 0.889 0)
			(size 1.016 1.27)
			(layers "B.Cu" "B.Mask" "B.Paste")
			(net "P12V_MEM_CPU0")
		)
		(pad "2" smd rect
			(at -0.889 0)
			(size 1.016 1.27)
			(layers "B.Cu" "B.Mask" "B.Paste")
			(net "GND")
		)
	)
	(footprint ""
		(layer "B.Cu")
		(at 411.546294 -396.393162 -90)
		(property "Reference" "C673"
			(at 0 0 90)
			(layer "B.SilkS")
			(hide yes)
			(effects
				(font
					(size 1.27 1.27)
				)
				(justify mirror)
			)
		)
		(property "Value" ""
			(at 0 0 90)
			(layer "B.Fab")
			(effects
				(font
					(size 1.27 1.27)
				)
				(justify mirror)
			)
		)
		(duplicate_pad_numbers_are_jumpers no)
		(fp_line
			(start -0.299974 0.150114)
			(end 0.299974 0.150114)
			(stroke
				(width 0.1)
				(type default)
			)
			(layer "B.Fab")
		)
		(fp_line
			(start 0.299974 0.150114)
			(end 0.299974 -0.150114)
			(stroke
				(width 0.1)
				(type default)
			)
			(layer "B.Fab")
		)
		(fp_line
			(start -0.299974 -0.150114)
			(end -0.299974 0.150114)
			(stroke
				(width 0.1)
				(type default)
			)
			(layer "B.Fab")
		)
		(fp_line
			(start 0.299974 -0.150114)
			(end -0.299974 -0.150114)
			(stroke
				(width 0.1)
				(type default)
			)
			(layer "B.Fab")
		)
		(pad "1" smd rect
			(at 0.2667 0 90)
			(size 0.3048 0.381)
			(layers "B.Cu" "B.Mask" "B.Paste")
			(net "P1V8_CPU0_RT2_1A")
		)
		(pad "2" smd rect
			(at -0.2667 0 90)
			(size 0.3048 0.381)
			(layers "B.Cu" "B.Mask" "B.Paste")
			(net "GND")
		)
	)
)
